# BASEBOARD_FAB2 (Tioga Pass) — schematic netlist excerpt (pin names and nets, part order shuffled) for the footprints in the layout excerpt that follows; sources: Cadence DE-HDL packaged netlist, KiCad conversion of Wiwynn_Tioga_Pass_MB.brd

R5N1  RES  10.0K 1% CHIP  pkg 0402  page 21 : A = P3V3_STBY ; B = FM_CPU0_PKGID0
C3P31  CAP  0.22UF 16V 10% X7R  pkg 0402  page 107 : A = P3E_CPU0_PE1_SS_TXP<5> ; B = P3E_CPU0_PE1_SS_C_TXP<5>
R25W155  RES  0.0 5% CHIP  pkg 0402  page 148 : A = PVCCIO_CPU0 ; B = PVCCIO_CPU0_R

(kicad_pcb
	(version 20260206)
	(generator "pcbnew")
	(generator_version "10.0")
	(general
		(thickness 1.6)
		(legacy_teardrops no)
	)
	(paper "A4")
	(title_block
		(title "Wiwynn_Tioga_Pass_MB.brd")
		(comment 1 "Tioga Pass / footprints 3703-3705 of 4770")
	)
	(layers
		(0 "F.Cu" signal "TOP")
		(4 "In1.Cu" signal "L2GND")
		(6 "In2.Cu" signal "L3")
		(8 "In3.Cu" signal "L4GND")
		(10 "In4.Cu" signal "L5")
		(12 "In5.Cu" signal "L6GND")
		(14 "In6.Cu" signal "L7VCC")
		(16 "In7.Cu" signal "L8VCC")
		(18 "In8.Cu" signal "L9GND")
		(20 "In9.Cu" signal "L10")
		(22 "In10.Cu" signal "L11GND")
		(24 "In11.Cu" signal "L12")
		(26 "In12.Cu" signal "L13GND")
		(2 "B.Cu" signal "BOTTOM")
		(9 "F.Adhes" user "F.Adhesive")
		(11 "B.Adhes" user "B.Adhesive")
		(13 "F.Paste" user "Package Geometry/Pastemask Top")
		(15 "B.Paste" user "Package Geometry/Pastemask Bottom")
		(5 "F.SilkS" user "Ref Des/Silkscreen Top")
		(7 "B.SilkS" user "Ref Des/Silkscreen Bottom")
		(1 "F.Mask" user "Board Geometry/Soldermask Top")
		(3 "B.Mask" user "Board Geometry/Soldermask Bottom")
		(17 "Dwgs.User" user "User.Drawings")
		(19 "Cmts.User" user "User.Comments")
		(21 "Eco1.User" user "User.Eco1")
		(23 "Eco2.User" user "User.Eco2")
		(25 "Edge.Cuts" user "Board Geometry/Outline")
		(27 "Margin" user)
		(31 "F.CrtYd" user "Package Geometry/Place Bound Top")
		(29 "B.CrtYd" user "Package Geometry/Place Bound Bottom")
		(35 "F.Fab" user "Ref Des/Assembly Top")
		(33 "B.Fab" user "Ref Des/Assembly Bottom")
	)
	(footprint ""
		(layer "B.Cu")
		(at 352.96729 -77.915516)
		(property "Reference" "C3P31"
			(at 0 0 0)
			(layer "B.SilkS")
			(hide yes)
			(effects
				(font
					(size 1.27 1.27)
				)
				(justify mirror)
			)
		)
		(property "Value" ""
			(at 0 0 0)
			(layer "B.Fab")
			(effects
				(font
					(size 1.27 1.27)
				)
				(justify mirror)
			)
		)
		(duplicate_pad_numbers_are_jumpers no)
		(fp_poly
			(pts
				(xy -0.3048 -0.1016) (xy -0.3048 0.9906) (xy 0.3048 0.9906) (xy 0.3048 -0.1016)
			)
			(stroke
				(width 0)
				(type default)
			)
			(fill no)
			(layer "B.CrtYd")
		)
		(fp_line
			(start -0.3048 -0.1016)
			(end 0.3048 -0.1016)
			(stroke
				(width 0.1)
				(type default)
			)
			(layer "B.Fab")
		)
		(fp_line
			(start -0.3048 0.9906)
			(end -0.3048 -0.1016)
			(stroke
				(width 0.1)
				(type default)
			)
			(layer "B.Fab")
		)
		(fp_line
			(start 0.3048 -0.1016)
			(end 0.3048 0.9906)
			(stroke
				(width 0.1)
				(type default)
			)
			(layer "B.Fab")
		)
		(fp_line
			(start 0.3048 0.9906)
			(end -0.3048 0.9906)
			(stroke
				(width 0.1)
				(type default)
			)
			(layer "B.Fab")
		)
		(pad "1" smd rect
			(at 0 0 180)
			(size 0.508 0.508)
			(layers "B.Cu" "B.Mask" "B.Paste")
			(net "P3E_CPU0_PE1_SS_TXP<5>")
		)
		(pad "2" smd rect
			(at 0 0.889 180)
			(size 0.508 0.508)
			(layers "B.Cu" "B.Mask" "B.Paste")
			(net "P3E_CPU0_PE1_SS_C_TXP<5>")
		)
		(zone
			(layer "B.Cu")
			(hatch none 0.5)
			(connect_pads
				(clearance 0)
			)
			(min_thickness 0.25)
			(keepout
				(tracks allowed)
				(vias not_allowed)
				(pads allowed)
				(copperpour not_allowed)
				(footprints allowed)
			)
			(placement
				(enabled no)
				(sheetname "")
			)
			(fill
				(thermal_gap 0.5)
				(thermal_bridge_width 0.5)
				(island_removal_mode 0)
			)
			(polygon
				(pts
					(xy 353.22129 -77.661516) (xy 352.71329 -77.661516) (xy 352.71329 -77.280516) (xy 353.22129 -77.280516)
				)
			)
		)
		(zone
			(layer "B.Cu")
			(hatch none 0.5)
			(connect_pads
				(clearance 0)
			)
			(min_thickness 0.25)
			(keepout
				(tracks not_allowed)
				(vias allowed)
				(pads allowed)
				(copperpour not_allowed)
				(footprints allowed)
			)
			(placement
				(enabled no)
				(sheetname "")
			)
			(fill
				(thermal_gap 0.5)
				(thermal_bridge_width 0.5)
				(island_removal_mode 0)
			)
			(polygon
				(pts
					(xy 353.22129 -77.280516) (xy 352.71329 -77.280516) (xy 352.71329 -77.661516) (xy 353.22129 -77.661516)
				)
			)
		)
	)
	(footprint ""
		(layer "B.Cu")
		(at 433.84089 -43.70578 90)
		(property "Reference" "R25W155"
			(at 0.8382 -0.67818 90)
			(unlocked yes)
			(layer "B.SilkS")
			(effects
				(font
					(size 0.4064 0.254)
					(thickness 0.1524)
				)
				(justify left mirror)
			)
		)
		(property "Value" ""
			(at 0 0 90)
			(layer "B.Fab")
			(effects
				(font
					(size 1.27 1.27)
				)
				(justify mirror)
			)
		)
		(duplicate_pad_numbers_are_jumpers no)
		(fp_poly
			(pts
				(xy 0.2794 -0.1016) (xy -0.2794 -0.1016) (xy -0.2794 0.9906) (xy 0.2794 0.9906)
			)
			(stroke
				(width 0)
				(type default)
			)
			(fill no)
			(layer "B.CrtYd")
		)
		(fp_line
			(start 0.2794 -0.1016)
			(end 0.2794 0.9906)
			(stroke
				(width 0.1)
				(type default)
			)
			(layer "B.Fab")
		)
		(fp_line
			(start -0.2794 -0.1016)
			(end 0.2794 -0.1016)
			(stroke
				(width 0.1)
				(type default)
			)
			(layer "B.Fab")
		)
		(fp_line
			(start 0.2794 0.9906)
			(end -0.2794 0.9906)
			(stroke
				(width 0.1)
				(type default)
			)
			(layer "B.Fab")
		)
		(fp_line
			(start -0.2794 0.9906)
			(end -0.2794 -0.1016)
			(stroke
				(width 0.1)
				(type default)
			)
			(layer "B.Fab")
		)
		(pad "1" smd rect
			(at 0 0 270)
			(size 0.508 0.508)
			(layers "B.Cu" "B.Mask" "B.Paste")
			(net "PVCCIO_CPU0")
		)
		(pad "2" smd rect
			(at 0 0.889 270)
			(size 0.508 0.508)
			(layers "B.Cu" "B.Mask" "B.Paste")
			(net "PVCCIO_CPU0_R")
		)
		(zone
			(layer "B.Cu")
			(hatch none 0.5)
			(connect_pads
				(clearance 0)
			)
			(min_thickness 0.25)
			(keepout
				(tracks allowed)
				(vias not_allowed)
				(pads allowed)
				(copperpour not_allowed)
				(footprints allowed)
			)
			(placement
				(enabled no)
				(sheetname "")
			)
			(fill
				(thermal_gap 0.5)
				(thermal_bridge_width 0.5)
				(island_removal_mode 0)
			)
			(polygon
				(pts
					(xy 434.09489 -43.95978) (xy 434.09489 -43.45178) (xy 434.47589 -43.45178) (xy 434.47589 -43.95978)
				)
			)
		)
		(zone
			(layer "B.Cu")
			(hatch none 0.5)
			(connect_pads
				(clearance 0)
			)
			(min_thickness 0.25)
			(keepout
				(tracks not_allowed)
				(vias allowed)
				(pads allowed)
				(copperpour not_allowed)
				(footprints allowed)
			)
			(placement
				(enabled no)
				(sheetname "")
			)
			(fill
				(thermal_gap 0.5)
				(thermal_bridge_width 0.5)
				(island_removal_mode 0)
			)
			(polygon
				(pts
					(xy 434.47589 -43.95978) (xy 434.47589 -43.45178) (xy 434.09489 -43.45178) (xy 434.09489 -43.95978)
				)
			)
		)
	)
	(footprint ""
		(layer "B.Cu")
		(at 227.584 -93.345 90)
		(property "Reference" "R5N1"
			(at 0 0 90)
			(layer "B.SilkS")
			(hide yes)
			(effects
				(font
					(size 1.27 1.27)
				)
				(justify mirror)
			)
		)
		(property "Value" ""
			(at 0 0 90)
			(layer "B.Fab")
			(effects
				(font
					(size 1.27 1.27)
				)
				(justify mirror)
			)
		)
		(duplicate_pad_numbers_are_jumpers no)
		(fp_poly
			(pts
				(xy 0.2794 -0.1016) (xy -0.2794 -0.1016) (xy -0.2794 0.9906) (xy 0.2794 0.9906)
			)
			(stroke
				(width 0)
				(type default)
			)
			(fill no)
			(layer "B.CrtYd")
		)
		(fp_line
			(start 0.2794 -0.1016)
			(end 0.2794 0.9906)
			(stroke
				(width 0.1)
				(type default)
			)
			(layer "B.Fab")
		)
		(fp_line
			(start -0.2794 -0.1016)
			(end 0.2794 -0.1016)
			(stroke
				(width 0.1)
				(type default)
			)
			(layer "B.Fab")
		)
		(fp_line
			(start 0.2794 0.9906)
			(end -0.2794 0.9906)
			(stroke
				(width 0.1)
				(type default)
			)
			(layer "B.Fab")
		)
		(fp_line
			(start -0.2794 0.9906)
			(end -0.2794 -0.1016)
			(stroke
				(width 0.1)
				(type default)
			)
			(layer "B.Fab")
		)
		(pad "1" smd rect
			(at 0 0 270)
			(size 0.508 0.508)
			(layers "B.Cu" "B.Mask" "B.Paste")
			(net "P3V3_STBY")
		)
		(pad "2" smd rect
			(at 0 0.889 270)
			(size 0.508 0.508)
			(layers "B.Cu" "B.Mask" "B.Paste")
			(net "FM_CPU0_PKGID0")
		)
		(zone
			(layer "B.Cu")
			(hatch none 0.5)
			(connect_pads
				(clearance 0)
			)
			(min_thickness 0.25)
			(keepout
				(tracks allowed)
				(vias not_allowed)
				(pads allowed)
				(copperpour not_allowed)
				(footprints allowed)
			)
			(placement
				(enabled no)
				(sheetname "")
			)
			(fill
				(thermal_gap 0.5)
				(thermal_bridge_width 0.5)
				(island_removal_mode 0)
			)
			(polygon
				(pts
					(xy 227.838 -93.599) (xy 227.838 -93.091) (xy 228.219 -93.091) (xy 228.219 -93.599)
				)
			)
		)
		(zone
			(layer "B.Cu")
			(hatch none 0.5)
			(connect_pads
				(clearance 0)
			)
			(min_thickness 0.25)
			(keepout
				(tracks not_allowed)
				(vias allowed)
				(pads allowed)
				(copperpour not_allowed)
				(footprints allowed)
			)
			(placement
				(enabled no)
				(sheetname "")
			)
			(fill
				(thermal_gap 0.5)
				(thermal_bridge_width 0.5)
				(island_removal_mode 0)
			)
			(polygon
				(pts
					(xy 228.219 -93.599) (xy 228.219 -93.091) (xy 227.838 -93.091) (xy 227.838 -93.599)
				)
			)
		)
	)
)
